#ISCELL
  pure_quanta quanta_title_block_c *
  *
#CELL
  pure_quanta q_cap *
  page74_i1
#CELL
  pure_quanta q_cap *
  page74_i10
#CELL
  pure_quanta q_cap *
  page74_i11
#CELL
  pure_quanta q_cap *
  page74_i12
#CELL
  pure_quanta q_cap *
  page74_i13
#CELL
  pure_quanta q_cap *
  page74_i14
#CELL
  pure_quanta q_cap *
  page74_i15
#CELL
  pure_quanta q_cap *
  page74_i16
#ISCELL
  pure_quanta_power universal_gnd *
  page74_i17
#CELL
  pure_quanta q_cap *
  page74_i18
#ISCELL
  pure_quanta_power universal_gnd *
  page74_i19
#ISCELL
  pure_quanta_power universal_power *
  page74_i2
#CELL
  pure_quanta q_cap *
  page74_i20
#CELL
  pure_quanta q_cap *
  page74_i3
#ISCELL
  pure_quanta_power universal_power *
  page74_i4
#CELL
  pure_quanta q_cap *
  page74_i5
#ISCELL
  pure_quanta_power universal_power *
  page74_i6
#ISCELL
  pure_quanta_power universal_gnd *
  page74_i7
#CELL
  pure_quanta q_cap *
  page74_i8
#CELL
  pure_quanta q_cap *
  page74_i9
